FILE_TYPE = CONNECTIVITY;
{Allegro Design Entry HDL 17.2-2016 S081 (4005846) 1/11/2022}
"PAGE_NUMBER" = 152;
0"NC";
1"P3V3_AUX\g";
2"P3V3_AUX\g";
3"P3V3_AUX\g";
4"P3V3_AUX\g";
5"P3V3_AUX\g";
6"P3V3_AUX\g";
7"P3V3_AUX\g";
8"P3V3_AUX\g"$PHYS_NET_NAME"P3V3_AUX"CDS_PHYS_NET_NAME"P3V3_AUX"VOLTAGE"3.3";
9"P3V3_OCP_SFF\g";
10"P3V3_AUX\g";
11"P3V3_AUX\g";
12"GND\g";
13"GND\g";
14"GND\g";
15"GND\g";
16"GND\g";
17"GND\g";
18"GND\g";
19"GND\g";
20"GND\g";
21"GND\g";
22"GND\g";
23"GND\g";
24"GND\g";
25"GND\g";
26"OCP_SFF_PWRBRK_BUFF_N"CDS_PHYS_NET_NAME"OCP_SFF_PWRBRK_R_N";
27"RST_PERST2_OCP_SFF_N"CDS_PHYS_NET_NAME"RST_PLTRST_B_N";
28"RST_PERST3_OCP_SFF_N"CDS_PHYS_NET_NAME"RST_PLTRST_B_N";
29"RST_OCP_V3_1_BUF_N"CDS_PHYS_NET_NAME"RST_PLTRST_B_N";
30"NC_U157_NC1"CDS_PHYS_NET_NAME"RST_PLTRST_B_N";
31"CLK_50M_NCSI_OCP_SFF"CDS_PHYS_NET_NAME"TP_CLK_50M_NCSI_OCP_LFF_4CP";
32"CLK_50M_NCSI_OCP_SFF_ISO_R"CDS_PHYS_NET_NAME"TP_CLK_50M_NCSI_OCP_LFF_4CP";
33"FB_BMC_ISOLATE";
34"CLK_50M_NCSI_OCP_SFF_ISO"CDS_PHYS_NET_NAME"TP_CLK_50M_NCSI_OCP_LFF_4CP";
35"FM_SYS_THROTTLE_R_N"CDS_PHYS_NET_NAME"RST_PLTRST_B_N";
36"NC_U104_NC1"CDS_PHYS_NET_NAME"RST_PLTRST_B_N";
37"OCP_SFF_PWRBRK_N"CDS_PHYS_NET_NAME"OCP_SFF_PWRBRK_N";
38"OCP_SFF_WAKE_BUFF_R_N"CDS_PHYS_NET_NAME"FB_BMC_RBT_ISOLATE_N";
39"IRQ_LVC3_OCP_SFF_WAKE_N"CDS_PHYS_NET_NAME"FB_BMC_RBT_ISOLATE_N";
40"RST_PERST1_OCP_SFF_N"CDS_PHYS_NET_NAME"RST_PLTRST_B_N";
41"RST_PERST0_OCP_SFF_N"CDS_PHYS_NET_NAME"RST_PLTRST_B_N";
42"RST_HP_OCP_V3_1_N"CDS_PHYS_NET_NAME"FB_BMC_RBT_ISOLATE_N";
43"OCP_SFF_WAKE_BUFF_N"CDS_PHYS_NET_NAME"FB_BMC_RBT_ISOLATE_N";
44"CLK_50M_RMII";
45"CLK_50M_NCSI_OCP_1"CDS_PHYS_NET_NAME"TP_CLK_50M_NCSI_OCP_LFF_4CP";
46"PU_OCP_SFF_WAKE_OE"CDS_PHYS_NET_NAME"FB_BMC_RBT_ISOLATE_N";
47"CLK_50M_BMC_MAC_R"CDS_PHYS_NET_NAME"TP_CLK_50M_NCSI_OCP_LFF_4CP";
48"CLK_50M_NCSI_OCP_2"CDS_PHYS_NET_NAME"TP_CLK_50M_NCSI_OCP_LFF_4CP";
49"TP_CLK_50M_PCH_LOM"CDS_PHYS_NET_NAME"TP_CLK_50M_NCSI_OCP_LFF_4CP";
50"IRQ_LVC3_WAKE_BUF_N"CDS_PHYS_NET_NAME"IRQ_LVC3_WAKE_N";
51"CLK_50M_EN";
52"CLK_50M_RMII_R";
53"IRQ_LVC3_WAKE_N"CDS_PHYS_NET_NAME"IRQ_LVC3_WAKE_N";
54"CLK_50M_RMII_BMC_OCP"CDS_PHYS_NET_NAME"TP_CLK_50M_NCSI_OCP_LFF_4CP";
55"CLK_50M_NCSI_OCP_V3_2"CDS_PHYS_NET_NAME"TP_CLK_50M_NCSI_OCP_LFF_4CP";
56"CLK_50M_NCSI_OCP_SFF"CDS_PHYS_NET_NAME"TP_CLK_50M_NCSI_OCP_LFF_4CP";
%"74LVC1G17GW"
"1","(-7700,7225)","0","pure_quanta","I1";
;
PART_NUMBER"AL1G0017K01"
PART_TYPE"SMLF"
VALUE"74LVC1G17GW"
MATERIAL"IC"
$LOCATION"U75"
PIN_NAMES_ROTATE"True"
CDS_LMAN_SYM_OUTLINE"-125,150,125,-150"
CDS_LIB"pure_quanta"
SEC_TYPE""
CDS_LOCATION"U75"
SEC"1";
"NC"
$PN"1"0;
"Y"
$PN"4"29;
"GND"
$PN"3"22;
"A"
$PN"2"42;
"VCC"
$PN"5"11;
%"Q_RES"
"1","(-6250,6775)","0","pure_quanta","I10";
;
PART_NUMBER"CS03322FB03"
PACK_TYPE"0402LF"
VALUE"33.2"
TOLERANCE"1%"
WATTAGE"1/16W"
MATERIAL"CHIP"
$LOCATION"R1504"
CDS_LIB"pure_quanta"
CDS_LOCATION"R1504"
$SEC"1"
CDS_SEC"1";
"B"
$PN"2"27;
"A"
$PN"1"29;
%"Q_RES"
"1","(-6250,6550)","0","pure_quanta","I13";
;
PART_NUMBER"CS03322FB03"
MATERIAL"CHIP"
VALUE"33.2"
WATTAGE"1/16W"
PACK_TYPE"0402LF"
TOLERANCE"1%"
$LOCATION"R1505"
CDS_LIB"pure_quanta"
CDS_LOCATION"R1505"
$SEC"1"
CDS_SEC"1";
"B"
$PN"2"28;
"A"
$PN"1"29;
%"UNIVERSAL_GND"
"1","(-7875,6975)","0","logical_power","I14";
;
CDS_LIB"logical_power"
HDL_POWER"GND";
"A"22;
%"Q_CAP"
"1","(-8075,4650)","0","pure_quanta","I24";
;
PART_NUMBER"CH4104K1B00"
VALUE"0.1UF"
TOLERANCE"10%"
MATERIAL"X7R"
PACK_TYPE"0402"
VOLTAGE"25V"
$LOCATION"C1175"
CDS_LIB"pure_quanta"
CDS_LOCATION"C1175"
$SEC"1"
CDS_SEC"1";
"B"
$PN"2"21;
"A"
$PN"1"8;
%"UNIVERSAL_GND"
"1","(-8075,4425)","0","logical_power","I25";
;
CDS_LIB"logical_power"
HDL_POWER"GND";
"A"21;
%"Q_RES"
"1","(-6900,4100)","0","pure_quanta","I26";
;
PART_NUMBER"CS03322FB03"
PACK_TYPE"0402LF"
VALUE"33.2"
TOLERANCE"1%"
MATERIAL"CHIP"
WATTAGE"1/16W"
$LOCATION"R1594"
CDS_LIB"pure_quanta"
CDS_LOCATION"R1594"
$SEC"1"
CDS_SEC"1";
"B"
$PN"2"38;
"A"
$PN"1"43;
%"UNIVERSAL_GND"
"1","(-8200,7325)","0","logical_power","I3";
;
CDS_LIB"logical_power"
HDL_POWER"GND";
"A"25;
%"UNIVERSAL_GND"
"1","(-7900,5350)","0","logical_power","I32";
;
CDS_LIB"logical_power"
HDL_POWER"GND";
"A"24;
%"UNIVERSAL_POWER"
"1","(-8075,5000)","0","logical_power","I36";
;
HDL_POWER"P3V3_AUX"
CDS_LIB"logical_power";
"A"8;
%"Q_RES"
"2","(-9575,4475)","0","pure_quanta","I37";
;
PART_NUMBER"CS31002FB08"
PACK_TYPE"0402LF"
VALUE"10K"
WATTAGE"1/16W"
TOLERANCE"1%"
MATERIAL"CHIP"
$LOCATION"R1592"
CDS_LIB"pure_quanta"
CDS_LOCATION"R1592"
$SEC"1"
CDS_SEC"1";
"A"
$PN"1"9;
"B"
$PN"2"46;
%"UNIVERSAL_POWER"
"1","(-9575,4825)","0","logical_power","I38";
;
HDL_POWER"P3V3_OCP_SFF"
CDS_LIB"logical_power";
"A"9;
%"Q_CAP"
"1","(-8200,7550)","2","pure_quanta","I4";
;
PART_NUMBER"CH4104K1B00"
VOLTAGE"25V"
PACK_TYPE"0402"
VALUE"0.1UF"
TOLERANCE"10%"
MATERIAL"X7R"
$LOCATION"C1173"
CDS_LIB"pure_quanta"
CDS_LOCATION"C1173"
$SEC"1"
CDS_SEC"1";
"B"
$PN"2"25;
"A"
$PN"1"11;
%"Q_RES"
"1","(-5500,5575)","0","pure_quanta","I40";
;
PART_NUMBER"CS03322FB03"
TOLERANCE"1%"
PACK_TYPE"0402LF"
VALUE"33.2"
WATTAGE"1/16W"
MATERIAL"CHIP"
$LOCATION"R1595"
CDS_LIB"pure_quanta"
CDS_LOCATION"R1595"
$SEC"1"
CDS_SEC"1";
"B"
$PN"2"37;
"A"
$PN"1"26;
%"UNIVERSAL_POWER"
"1","(-6050,6150)","0","logical_power","I41";
;
HDL_POWER"P3V3_AUX"
CDS_LIB"logical_power";
"A"2;
%"Q_RES"
"2","(-6050,5950)","0","pure_quanta","I42";
;
PART_NUMBER"CS24702FB06"
MATERIAL"CHIP"
WATTAGE"1/16W"
TOLERANCE"1%"
VALUE"4.7K"
PACK_TYPE"0402LF"
$LOCATION"R1593"
CDS_LIB"pure_quanta"
CDS_LOCATION"R1593"
$SEC"1"
CDS_SEC"1";
"A"
$PN"1"2;
"B"
$PN"2"26;
%"UNIVERSAL_POWER"
"1","(-6950,6325)","0","logical_power","I43";
;
HDL_POWER"P3V3_AUX"
CDS_LIB"logical_power";
"A"1;
%"Q_CAP"
"1","(-6750,6050)","0","pure_quanta","I44";
;
PART_NUMBER"CH4104K1B00"
PACK_TYPE"0402"
VALUE"0.1UF"
VOLTAGE"25V"
TOLERANCE"10%"
MATERIAL"X7R"
$LOCATION"C188"
CDS_LIB"pure_quanta"
CDS_LOCATION"C188"
$SEC"1"
CDS_SEC"1";
"B"
$PN"2"23;
"A"
$PN"1"1;
%"UNIVERSAL_GND"
"1","(-6750,5825)","0","logical_power","I45";
;
CDS_LIB"logical_power"
HDL_POWER"GND";
"A"23;
%"PI6CV304LE"
"1","(-7150,2300)","0","pure_quanta","I46";
;
PART_NUMBER"AL000304K01"
MATERIAL"IC"
VALUE"PI6CV304LE"
PART_TYPE"SMLF"
$LOCATION"U90"
CDS_LMAN_SYM_OUTLINE"-150,225,150,-225"
CDS_LIB"pure_quanta"
CDS_LOCATION"U90"
$SEC"1"
CDS_SEC"1";
"GND"
$PN"4"17;
"VDD"
$PN"6"6;
"Y3"
$PN"8"49;
"Y2"
$PN"7"48;
"Y1"
$PN"5"45;
"Y0"
$PN"3"47;
"OE"
$PN"2"51;
"CLK_IN"
$PN"1"52;
%"UNIVERSAL_POWER"
"1","(-6650,3025)","0","logical_power","I47";
;
HDL_POWER"P3V3_AUX"
CDS_LIB"logical_power";
"A"6;
%"UNIVERSAL_POWER"
"1","(-9950,2975)","0","logical_power","I48";
;
HDL_POWER"P3V3_AUX"
CDS_LIB"logical_power";
"A"7;
%"Q_CAP"
"1","(-6425,2700)","0","pure_quanta","I49";
;
PART_NUMBER"CH4104K1B00"
VOLTAGE"25V"
MATERIAL"X7R"
VALUE"0.1UF"
TOLERANCE"10%"
PACK_TYPE"0402"
$LOCATION"C1275"
CDS_LIB"pure_quanta"
CDS_LOCATION"C1275"
$SEC"1"
CDS_SEC"1";
"B"
$PN"2"16;
"A"
$PN"1"6;
%"UNIVERSAL_POWER"
"1","(-8000,7825)","0","logical_power","I5";
;
HDL_POWER"P3V3_AUX"
CDS_LIB"logical_power";
"A"11;
%"Q_RES"
"1","(-5725,2375)","0","pure_quanta","I52";
;
PART_NUMBER"CS02742FB03"
TOLERANCE"1%"
VALUE"27.4"
PACK_TYPE"0402LF"
WATTAGE"1/16W"
MATERIAL"CHIP"
$LOCATION"R1140"
CDS_LIB"pure_quanta"
CDS_LOCATION"R1140"
$SEC"1"
CDS_SEC"1";
"B"
$PN"2"54;
"A"
$PN"1"47;
%"Q_RES"
"1","(-5725,2325)","0","pure_quanta","I53";
;
PART_NUMBER"CS02742FB03"
VALUE"27.4"
TOLERANCE"1%"
MATERIAL"CHIP"
$LOCATION"R1141"
PACK_TYPE"0402LF"
CDS_LIB"pure_quanta"
WATTAGE"1/16W"
CDS_LOCATION"R1141"
$SEC"1"
CDS_SEC"1";
"B"
$PN"2"56;
"A"
$PN"1"45;
%"UNIVERSAL_GND"
"1","(-6425,2475)","0","logical_power","I54";
;
CDS_LIB"logical_power"
HDL_POWER"GND";
"A"16;
%"UNIVERSAL_GND"
"1","(-6725,2000)","0","logical_power","I55";
;
CDS_LIB"logical_power"
HDL_POWER"GND"
ROOM"IO_SLOT";
"A"17;
%"Q_RES"
"1","(-8325,2375)","0","pure_quanta","I56";
;
PART_NUMBER"CS00002JB13"
WATTAGE"1/16W"
PACK_TYPE"0402LF"
MATERIAL"CHIP"
VALUE"0"
TOLERANCE"5%"
$LOCATION"R1139"
CDS_LIB"pure_quanta"
CDS_LOCATION"R1139"
$SEC"1"
CDS_SEC"1";
"B"
$PN"2"52;
"A"
$PN"1"44;
%"UNIVERSAL_GND"
"1","(-9000,2100)","0","logical_power","I57";
;
CDS_LIB"logical_power"
HDL_POWER"GND"
ROOM"IO_SLOT";
"A"18;
%"Q_CAP"
"1","(-10050,2600)","2","pure_quanta","I59";
;
PART_NUMBER"CH4104K1B00"
TOLERANCE"10%"
VALUE"0.1UF"
VOLTAGE"25V"
MATERIAL"X7R"
PACK_TYPE"0402"
$LOCATION"C1274"
CDS_LIB"pure_quanta"
CDS_LOCATION"C1274"
$SEC"1"
CDS_SEC"1";
"B"
$PN"2"19;
"A"
$PN"1"7;
%"Q_RES"
"1","(-6250,7225)","0","pure_quanta","I6";
;
PART_NUMBER"CS03322FB03"
PACK_TYPE"0402LF"
TOLERANCE"1%"
VALUE"33.2"
MATERIAL"CHIP"
WATTAGE"1/16W"
$LOCATION"R419"
CDS_LIB"pure_quanta"
CDS_LOCATION"R419"
$SEC"1"
CDS_SEC"1";
"B"
$PN"2"41;
"A"
$PN"1"29;
%"UNIVERSAL_GND"
"1","(-10050,2375)","0","logical_power","I60";
;
CDS_LIB"logical_power"
HDL_POWER"GND"
ROOM"IO_SLOT";
"A"19;
%"Q_RES"
"2","(-10400,2575)","2","pure_quanta","I61";
;
PART_NUMBER"CS31002FB08"
WATTAGE"1/16W"
TOLERANCE"1%"
VALUE"10K"
MATERIAL"CHIP"
PACK_TYPE"0402LF"
$LOCATION"R1138"
CDS_LIB"pure_quanta"
CDS_LOCATION"R1138"
$SEC"1"
CDS_SEC"1";
"A"
$PN"1"7;
"B"
$PN"2"51;
%"Q_RES"
"2","(-9850,4475)","2","pure_quanta","I62";
;
PART_NUMBER"CS31002FB08"
PACK_TYPE"0402LF"
MATERIAL"CHIP"
WATTAGE"1/16W"
TOLERANCE"1%"
VALUE"10K"
$LOCATION"R1824"
CDS_LIB"pure_quanta"
CDS_LOCATION"R1824"
$SEC"1"
CDS_SEC"1";
"A"
$PN"1"9;
"B"
$PN"2"39;
%"74LVC1G07GV"
"1","(-7425,5675)","0","pure_quanta","I63";
;
PART_NUMBER"AL1G0007001"
PART_TYPE"SMLF"
VALUE"74LVC1G07GV"
MATERIAL"IC"
$LOCATION"U104"
CDS_LMAN_SYM_OUTLINE"-125,150,125,-150"
NEEDS_NO_SIZE"TRUE"
CDS_LIB"pure_quanta"
CDS_LOCATION"U104"
$SEC"1"
CDS_SEC"1";
"NC1"
$PN"1"36;
"Y"
$PN"4"26;
"GND"
$PN"3"24;
"A"
$PN"2"35;
"VCC"
$PN"5"1;
%"74LVC1G07GV"
"1","(-5125,4100)","0","pure_quanta","I65";
;
PART_NUMBER"AL1G0007001"
MATERIAL"IC"
PART_TYPE"SMLF"
VALUE"74LVC1G07GV"
$LOCATION"U157"
CDS_LIB"pure_quanta"
CDS_LMAN_SYM_OUTLINE"-125,150,125,-150"
NEEDS_NO_SIZE"TRUE"
CDS_LOCATION"U157"
$SEC"1"
CDS_SEC"1";
"NC1"
$PN"1"30;
"Y"
$PN"4"50;
"GND"
$PN"3"15;
"A"
$PN"2"38;
"VCC"
$PN"5"5;
%"UNIVERSAL_GND"
"1","(-5600,3775)","0","logical_power","I66";
;
CDS_LIB"logical_power"
HDL_POWER"GND";
"A"15;
%"UNIVERSAL_POWER"
"1","(-4700,4650)","0","logical_power","I67";
;
HDL_POWER"P3V3_AUX"
CDS_LIB"logical_power";
"A"5;
%"Q_CAP"
"1","(-4500,4375)","0","pure_quanta","I68";
;
PART_NUMBER"CH4104K1B00"
VALUE"0.1UF"
VOLTAGE"25V"
TOLERANCE"10%"
MATERIAL"X7R"
PACK_TYPE"0402"
$LOCATION"C1663"
CDS_LIB"pure_quanta"
CDS_LOCATION"C1663"
$SEC"1"
CDS_SEC"1";
"B"
$PN"2"14;
"A"
$PN"1"5;
%"UNIVERSAL_GND"
"1","(-4500,4150)","0","logical_power","I69";
;
CDS_LIB"logical_power"
HDL_POWER"GND";
"A"14;
%"Q_RES"
"2","(-3950,4450)","0","pure_quanta","I71";
;
PART_NUMBER"CS24702FB06"
MATERIAL"EMPTY"
PACK_TYPE"0402LF"
TOLERANCE"1%"
WATTAGE"1/16W"
VALUE"4.7K"
$LOCATION"R2487"
CDS_LIB"pure_quanta"
CDS_LOCATION"R2487"
$SEC"1"
CDS_SEC"1";
"A"
$PN"1"10;
"B"
$PN"2"50;
%"UNIVERSAL_POWER"
"1","(-3950,4650)","0","logical_power","I72";
;
HDL_POWER"P3V3_AUX"
CDS_LIB"logical_power";
"A"10;
%"UNIVERSAL_POWER"
"1","(-7225,4750)","0","logical_power","I73";
;
HDL_POWER"P3V3_AUX"
CDS_LIB"logical_power";
"A"3;
%"Q_RES"
"2","(-7225,4550)","0","pure_quanta","I74";
;
PART_NUMBER"CS24702FB06"
MATERIAL"CHIP"
TOLERANCE"1%"
PACK_TYPE"0402LF"
WATTAGE"1/16W"
VALUE"4.7K"
$LOCATION"R2488"
CDS_LIB"pure_quanta"
CDS_LOCATION"R2488"
$SEC"1"
CDS_SEC"1";
"A"
$PN"1"3;
"B"
$PN"2"43;
%"Q_RES"
"1","(-3650,4000)","0","pure_quanta","I75";
;
PART_NUMBER"CS03322FB03"
WATTAGE"1/16W"
VALUE"33.2"
TOLERANCE"1%"
PACK_TYPE"0402LF"
MATERIAL"CHIP"
$LOCATION"R2489"
CDS_LIB"pure_quanta"
CDS_LOCATION"R2489"
$SEC"1"
CDS_SEC"1";
"B"
$PN"2"53;
"A"
$PN"1"50;
%"Q_OSC4P"
"1","(-9450,2300)","0","pure_quanta","I76";
;
PART_NUMBER"BF650000032"
MATERIAL"OSC"
PACK_TYPE"SMLF"
VALUE"50MHZ"
LOCATION"OSC1"
NEEDS_NO_SIZE"TRUE"
CDS_LIB"pure_quanta"
$SEC"1"
CDS_SEC"1";
"VDD"
$PN"4"7;
"OUT"
$PN"3"44;
"GND"
$PN"2"18;
"OE"
$PN"1"51;
%"Q_RES"
"1","(-5725,2275)","0","pure_quanta","I78";
;
PART_NUMBER"CS02742FB03"
MATERIAL"CHIP"
VALUE"27.4"
TOLERANCE"1%"
$LOCATION"R3181"
WATTAGE"1/16W"
CDS_LIB"pure_quanta"
PACK_TYPE"0402LF"
CDS_LOCATION"R3181"
$SEC"1"
CDS_SEC"1";
"B"
$PN"2"55;
"A"
$PN"1"48;
%"74LVC1G126SE7"
"1","(-8350,4100)","0","pure_quanta","I79";
;
PART_NUMBER"AL1G0126009"
MATERIAL"IC"
PART_TYPE"SMLF"
VALUE"74LVC1G126SE-7"
LOCATION"U82"
CDS_LIB"pure_quanta"
CDS_LMAN_SYM_OUTLINE"-100,100,100,-100"
NEEDS_NO_SIZE"TRUE"
$SEC"1"
CDS_SEC"1";
"OE"
$PN"1"46;
"GND"
$PN"3"20;
"VCC"
$PN"5"8;
"Y"
$PN"4"43;
"A"
$PN"2"39;
%"Q_RES"
"1","(-6250,7000)","0","pure_quanta","I8";
;
PART_NUMBER"CS03322FB03"
VALUE"33.2"
TOLERANCE"1%"
PACK_TYPE"0402LF"
WATTAGE"1/16W"
MATERIAL"CHIP"
$LOCATION"R435"
CDS_LIB"pure_quanta"
CDS_LOCATION"R435"
$SEC"1"
CDS_SEC"1";
"B"
$PN"2"40;
"A"
$PN"1"29;
%"UNIVERSAL_GND"
"1","(-8350,3650)","0","logical_power","I80";
;
CDS_LIB"logical_power"
HDL_POWER"GND";
"A"20;
%"UNIVERSAL_GND"
"1","(-3775,2875)","0","logical_power","I84";
;
CDS_LIB"logical_power"
HDL_POWER"GND";
"A"12;
%"UNIVERSAL_POWER"
"1","(-2900,3675)","0","logical_power","I85";
;
HDL_POWER"P3V3_AUX"
CDS_LIB"logical_power";
"A"4;
%"UNIVERSAL_GND"
"1","(-2700,3175)","0","logical_power","I86";
;
CDS_LIB"logical_power"
HDL_POWER"GND";
"A"13;
%"Q_CAP"
"1","(-2700,3400)","0","pure_quanta","I87";
;
PART_NUMBER"CH4104K1B00"
VOLTAGE"25V"
VALUE"0.1UF"
TOLERANCE"10%"
MATERIAL"X7R"
PACK_TYPE"0402"
$LOCATION"C2344"
CDS_LIB"pure_quanta"
CDS_LOCATION"C2344"
$SEC"1"
CDS_SEC"1";
"B"
$PN"2"13;
"A"
$PN"1"4;
%"Q_RES"
"1","(-4800,3125)","0","pure_quanta","I90";
;
PART_NUMBER"CS00002JB13"
VALUE"0"
MATERIAL"CHIP"
$LOCATION"R4601"
CDS_LIB"pure_quanta"
PACK_TYPE"0402LF"
TOLERANCE"5%"
WATTAGE"1/16W"
CDS_LOCATION"R4601"
$SEC"1"
CDS_SEC"1";
"B"
$PN"2"32;
"A"
$PN"1"34;
%"74LVC1G66GV"
"1","(-3350,3125)","0","pure_quanta","I92";
;
PART_NUMBER"AL001G66000"
VALUE"74LVC1G66GV"
PART_TYPE"SMLF"
MATERIAL"IC"
LOCATION"U320"
CDS_LMAN_SYM_OUTLINE"-150,150,150,-150"
CDS_LIB"pure_quanta"
PIN_NAMES_ROTATE"True"
$SEC"1"
CDS_SEC"1";
"VCC"
$PN"5"4;
"E"
$PN"4"33;
"GND"
$PN"3"12;
"Z"
$PN"2"32;
"Y"
$PN"1"31;
END.
